(kicad_pcb
	(version 20260206)
	(generator "pcbnew")
	(generator_version "10.0")
	(general
		(thickness 1.6)
		(legacy_teardrops no)
	)
	(paper "A4")
	(title_block
		(title "peb — Lightning_PEB_BRD.brd")
		(comment 1 "Lightning (Wiwynn / Facebook NVMe JBOF) / footprints 177-183 of 2563")
	)
	(layers
		(0 "F.Cu" signal "TOP")
		(4 "In1.Cu" signal "L2GND")
		(6 "In2.Cu" signal "L3")
		(8 "In3.Cu" signal "L4VCC")
		(10 "In4.Cu" signal "L5VCC")
		(12 "In5.Cu" signal "L6")
		(14 "In6.Cu" signal "L7GND")
		(2 "B.Cu" signal "BOTTOM")
		(9 "F.Adhes" user "F.Adhesive")
		(11 "B.Adhes" user "B.Adhesive")
		(13 "F.Paste" user "Package Geometry/Pastemask Top")
		(15 "B.Paste" user "Package Geometry/Pastemask Bottom")
		(5 "F.SilkS" user "Ref Des/Silkscreen Top")
		(7 "B.SilkS" user "Ref Des/Silkscreen Bottom")
		(1 "F.Mask" user "Board Geometry/Soldermask Top")
		(3 "B.Mask" user "Board Geometry/Soldermask Bottom")
		(17 "Dwgs.User" user "User.Drawings")
		(19 "Cmts.User" user "User.Comments")
		(21 "Eco1.User" user "User.Eco1")
		(23 "Eco2.User" user "User.Eco2")
		(25 "Edge.Cuts" user "Board Geometry/Outline")
		(27 "Margin" user)
		(31 "F.CrtYd" user "Package Geometry/Place Bound Top")
		(29 "B.CrtYd" user "Package Geometry/Place Bound Bottom")
		(35 "F.Fab" user "Ref Des/Assembly Top")
		(33 "B.Fab" user "Ref Des/Assembly Bottom")
	)
	(footprint ""
		(layer "F.Cu")
		(at 158.242 -98.7044 180)
		(property "Reference" "R101"
			(at 0 0 180)
			(layer "F.SilkS")
			(hide yes)
			(effects
				(font
					(size 1.27 1.27)
				)
			)
		)
		(property "Value" "10KR2F-2-GP"
			(at 0.064008 -3.993896 180)
			(unlocked yes)
			(layer "F.Fab")
			(hide yes)
			(effects
				(font
					(size 1.016 1.016)
					(thickness 0.1524)
				)
			)
		)
		(property "Device Type" "R402H16"
			(at 0.064008 -5.517896 180)
			(unlocked yes)
			(layer "F.Fab")
			(hide yes)
			(effects
				(font
					(size 1.016 1.016)
					(thickness 0.1524)
				)
			)
		)
		(duplicate_pad_numbers_are_jumpers no)
		(fp_line
			(start 0.508 -0.9398)
			(end -0.508 -0.9398)
			(stroke
				(width 0.1524)
				(type default)
			)
			(layer "F.SilkS")
		)
		(fp_line
			(start -0.508 -0.9398)
			(end -0.508 0.9398)
			(stroke
				(width 0.1524)
				(type default)
			)
			(layer "F.SilkS")
		)
		(fp_rect
			(start -0.508 0.9398)
			(end 0.508 -0.9398)
			(stroke
				(width 0)
				(type default)
			)
			(fill no)
			(layer "F.CrtYd")
		)
		(fp_rect
			(start -0.508 0.9398)
			(end 0.508 -0.9398)
			(stroke
				(width 0)
				(type default)
			)
			(fill no)
			(layer "F.Fab")
		)
		(pad "1" smd custom
			(at 0 -0.4445 180)
			(size 0.1397 0.1397)
			(layers "F.Cu" "F.Mask" "F.Paste")
			(net "CLKGEN_PWGD")
			(options
				(clearance outline)
				(anchor circle)
			)
			(primitives
				(gr_poly
					(pts
						(arc
							(start -0.1778 -0.2794)
							(mid -0.249642 -0.249642)
							(end -0.2794 -0.1778)
						)
						(arc
							(start -0.2794 0.1778)
							(mid -0.249642 0.249642)
							(end -0.1778 0.2794)
						)
						(arc
							(start 0.1778 0.2794)
							(mid 0.249642 0.249642)
							(end 0.2794 0.1778)
						)
						(arc
							(start 0.2794 -0.1778)
							(mid 0.249642 -0.249642)
							(end 0.1778 -0.2794)
						)
					)
					(width 0)
					(fill yes)
				)
			)
		)
		(pad "2" smd custom
			(at 0 0.4445 180)
			(size 0.1397 0.1397)
			(layers "F.Cu" "F.Mask" "F.Paste")
			(net "P1V8_STBY")
			(options
				(clearance outline)
				(anchor circle)
			)
			(primitives
				(gr_poly
					(pts
						(arc
							(start -0.1778 -0.2794)
							(mid -0.249642 -0.249642)
							(end -0.2794 -0.1778)
						)
						(arc
							(start -0.2794 0.1778)
							(mid -0.249642 0.249642)
							(end -0.1778 0.2794)
						)
						(arc
							(start 0.1778 0.2794)
							(mid 0.249642 0.249642)
							(end 0.2794 0.1778)
						)
						(arc
							(start 0.2794 -0.1778)
							(mid 0.249642 -0.249642)
							(end 0.1778 -0.2794)
						)
					)
					(width 0)
					(fill yes)
				)
			)
		)
	)
	(footprint ""
		(layer "F.Cu")
		(at 271.808194 -212.420454 180)
		(property "Reference" "C102"
			(at 0 0 180)
			(layer "F.SilkS")
			(hide yes)
			(effects
				(font
					(size 1.27 1.27)
				)
			)
		)
		(property "Value" "SCD22U10V2KX-1GP"
			(at 1.1811 -2.7051 180)
			(unlocked yes)
			(layer "F.Fab")
			(hide yes)
			(effects
				(font
					(size 1.016 1.016)
					(thickness 0.1524)
				)
			)
		)
		(property "Device Type" "C402H22"
			(at 1.1811 -4.2291 180)
			(unlocked yes)
			(layer "F.Fab")
			(hide yes)
			(effects
				(font
					(size 1.016 1.016)
					(thickness 0.1524)
				)
			)
		)
		(duplicate_pad_numbers_are_jumpers no)
		(fp_rect
			(start -0.4318 0.9525)
			(end 0.4318 -0.9525)
			(stroke
				(width 0)
				(type default)
			)
			(fill no)
			(layer "F.CrtYd")
		)
		(fp_rect
			(start -0.4318 0.9525)
			(end 0.4318 -0.9525)
			(stroke
				(width 0)
				(type default)
			)
			(fill no)
			(layer "F.Fab")
		)
		(pad "1" smd custom
			(at 0 -0.4445 180)
			(size 0.1524 0.1524)
			(layers "F.Cu" "F.Mask" "F.Paste")
			(net "PCIE_TX_CAP_N35")
			(options
				(clearance outline)
				(anchor circle)
			)
			(primitives
				(gr_poly
					(pts
						(arc
							(start 0.3048 -0.2032)
							(mid 0.275042 -0.275042)
							(end 0.2032 -0.3048)
						)
						(arc
							(start -0.2032 -0.3048)
							(mid -0.275042 -0.275042)
							(end -0.3048 -0.2032)
						)
						(arc
							(start -0.3048 0.2032)
							(mid -0.275042 0.275042)
							(end -0.2032 0.3048)
						)
						(arc
							(start 0.2032 0.3048)
							(mid 0.275042 0.275042)
							(end 0.3048 0.2032)
						)
					)
					(width 0)
					(fill yes)
				)
			)
		)
		(pad "2" smd custom
			(at 0 0.4445 180)
			(size 0.1524 0.1524)
			(layers "F.Cu" "F.Mask" "F.Paste")
			(net "PCIE_TX_N35")
			(options
				(clearance outline)
				(anchor circle)
			)
			(primitives
				(gr_poly
					(pts
						(arc
							(start 0.3048 -0.2032)
							(mid 0.275042 -0.275042)
							(end 0.2032 -0.3048)
						)
						(arc
							(start -0.2032 -0.3048)
							(mid -0.275042 -0.275042)
							(end -0.3048 -0.2032)
						)
						(arc
							(start -0.3048 0.2032)
							(mid -0.275042 0.275042)
							(end -0.2032 0.3048)
						)
						(arc
							(start 0.2032 0.3048)
							(mid 0.275042 0.275042)
							(end 0.3048 0.2032)
						)
					)
					(width 0)
					(fill yes)
				)
			)
		)
	)
	(footprint ""
		(layer "F.Cu")
		(at 46.355 -180.467)
		(property "Reference" "C253"
			(at 0 0 0)
			(layer "F.SilkS")
			(hide yes)
			(effects
				(font
					(size 1.27 1.27)
				)
			)
		)
		(property "Value" "SCD1U16V2KX-3GP"
			(at 1.1811 -2.7051 0)
			(unlocked yes)
			(layer "F.Fab")
			(hide yes)
			(effects
				(font
					(size 1.016 1.016)
					(thickness 0.1524)
				)
			)
		)
		(property "Device Type" "C402H22"
			(at 1.1811 -4.2291 0)
			(unlocked yes)
			(layer "F.Fab")
			(hide yes)
			(effects
				(font
					(size 1.016 1.016)
					(thickness 0.1524)
				)
			)
		)
		(duplicate_pad_numbers_are_jumpers no)
		(fp_rect
			(start -0.4318 0.9525)
			(end 0.4318 -0.9525)
			(stroke
				(width 0)
				(type default)
			)
			(fill no)
			(layer "F.CrtYd")
		)
		(fp_rect
			(start -0.4318 0.9525)
			(end 0.4318 -0.9525)
			(stroke
				(width 0)
				(type default)
			)
			(fill no)
			(layer "F.Fab")
		)
		(pad "1" smd custom
			(at 0 -0.4445)
			(size 0.1524 0.1524)
			(layers "F.Cu" "F.Mask" "F.Paste")
			(net "P3V3_STBY")
			(options
				(clearance outline)
				(anchor circle)
			)
			(primitives
				(gr_poly
					(pts
						(arc
							(start 0.3048 -0.2032)
							(mid 0.275042 -0.275042)
							(end 0.2032 -0.3048)
						)
						(arc
							(start -0.2032 -0.3048)
							(mid -0.275042 -0.275042)
							(end -0.3048 -0.2032)
						)
						(arc
							(start -0.3048 0.2032)
							(mid -0.275042 0.275042)
							(end -0.2032 0.3048)
						)
						(arc
							(start 0.2032 0.3048)
							(mid 0.275042 0.275042)
							(end 0.3048 0.2032)
						)
					)
					(width 0)
					(fill yes)
				)
			)
		)
		(pad "2" smd custom
			(at 0 0.4445)
			(size 0.1524 0.1524)
			(layers "F.Cu" "F.Mask" "F.Paste")
			(net "GND")
			(options
				(clearance outline)
				(anchor circle)
			)
			(primitives
				(gr_poly
					(pts
						(arc
							(start 0.3048 -0.2032)
							(mid 0.275042 -0.275042)
							(end 0.2032 -0.3048)
						)
						(arc
							(start -0.2032 -0.3048)
							(mid -0.275042 -0.275042)
							(end -0.3048 -0.2032)
						)
						(arc
							(start -0.3048 0.2032)
							(mid -0.275042 0.275042)
							(end -0.2032 0.3048)
						)
						(arc
							(start 0.2032 0.3048)
							(mid 0.275042 0.275042)
							(end 0.3048 0.2032)
						)
					)
					(width 0)
					(fill yes)
				)
			)
		)
	)
	(footprint ""
		(layer "F.Cu")
		(at 55.118 -180.467 180)
		(property "Reference" "R895"
			(at 0 0 180)
			(layer "F.SilkS")
			(hide yes)
			(effects
				(font
					(size 1.27 1.27)
				)
			)
		)
		(property "Value" "10KR2F-2-GP"
			(at 0.064008 -3.993896 180)
			(unlocked yes)
			(layer "F.Fab")
			(hide yes)
			(effects
				(font
					(size 1.016 1.016)
					(thickness 0.1524)
				)
			)
		)
		(property "Device Type" "R402H16"
			(at 0.064008 -5.517896 180)
			(unlocked yes)
			(layer "F.Fab")
			(hide yes)
			(effects
				(font
					(size 1.016 1.016)
					(thickness 0.1524)
				)
			)
		)
		(duplicate_pad_numbers_are_jumpers no)
		(fp_line
			(start 0.508 -0.9398)
			(end -0.508 -0.9398)
			(stroke
				(width 0.1524)
				(type default)
			)
			(layer "F.SilkS")
		)
		(fp_line
			(start -0.508 -0.9398)
			(end -0.508 0.9398)
			(stroke
				(width 0.1524)
				(type default)
			)
			(layer "F.SilkS")
		)
		(fp_rect
			(start -0.508 0.9398)
			(end 0.508 -0.9398)
			(stroke
				(width 0)
				(type default)
			)
			(fill no)
			(layer "F.CrtYd")
		)
		(fp_rect
			(start -0.508 0.9398)
			(end 0.508 -0.9398)
			(stroke
				(width 0)
				(type default)
			)
			(fill no)
			(layer "F.Fab")
		)
		(pad "1" smd custom
			(at 0 -0.4445 180)
			(size 0.1397 0.1397)
			(layers "F.Cu" "F.Mask" "F.Paste")
			(net "P3V3_STBY")
			(options
				(clearance outline)
				(anchor circle)
			)
			(primitives
				(gr_poly
					(pts
						(arc
							(start -0.1778 -0.2794)
							(mid -0.249642 -0.249642)
							(end -0.2794 -0.1778)
						)
						(arc
							(start -0.2794 0.1778)
							(mid -0.249642 0.249642)
							(end -0.1778 0.2794)
						)
						(arc
							(start 0.1778 0.2794)
							(mid 0.249642 0.249642)
							(end 0.2794 0.1778)
						)
						(arc
							(start 0.2794 -0.1778)
							(mid 0.249642 -0.249642)
							(end 0.1778 -0.2794)
						)
					)
					(width 0)
					(fill yes)
				)
			)
		)
		(pad "2" smd custom
			(at 0 0.4445 180)
			(size 0.1397 0.1397)
			(layers "F.Cu" "F.Mask" "F.Paste")
			(net "I2C8_BUFF_EN")
			(options
				(clearance outline)
				(anchor circle)
			)
			(primitives
				(gr_poly
					(pts
						(arc
							(start -0.1778 -0.2794)
							(mid -0.249642 -0.249642)
							(end -0.2794 -0.1778)
						)
						(arc
							(start -0.2794 0.1778)
							(mid -0.249642 0.249642)
							(end -0.1778 0.2794)
						)
						(arc
							(start 0.1778 0.2794)
							(mid 0.249642 0.249642)
							(end 0.2794 0.1778)
						)
						(arc
							(start 0.2794 -0.1778)
							(mid 0.249642 -0.249642)
							(end 0.1778 -0.2794)
						)
					)
					(width 0)
					(fill yes)
				)
			)
		)
	)
	(footprint ""
		(layer "F.Cu")
		(at 143.0274 -41.402 180)
		(property "Reference" "R757"
			(at 0 0 180)
			(layer "F.SilkS")
			(hide yes)
			(effects
				(font
					(size 1.27 1.27)
				)
			)
		)
		(property "Value" "0R2J-2-GP"
			(at 0.064008 -3.993896 180)
			(unlocked yes)
			(layer "F.Fab")
			(hide yes)
			(effects
				(font
					(size 1.016 1.016)
					(thickness 0.1524)
				)
			)
		)
		(property "Device Type" "R402H16"
			(at 0.064008 -5.517896 180)
			(unlocked yes)
			(layer "F.Fab")
			(hide yes)
			(effects
				(font
					(size 1.016 1.016)
					(thickness 0.1524)
				)
			)
		)
		(duplicate_pad_numbers_are_jumpers no)
		(fp_line
			(start 0.508 -0.9398)
			(end -0.508 -0.9398)
			(stroke
				(width 0.1524)
				(type default)
			)
			(layer "F.SilkS")
		)
		(fp_line
			(start -0.508 -0.9398)
			(end -0.508 0.9398)
			(stroke
				(width 0.1524)
				(type default)
			)
			(layer "F.SilkS")
		)
		(fp_rect
			(start -0.508 0.9398)
			(end 0.508 -0.9398)
			(stroke
				(width 0)
				(type default)
			)
			(fill no)
			(layer "F.CrtYd")
		)
		(fp_rect
			(start -0.508 0.9398)
			(end 0.508 -0.9398)
			(stroke
				(width 0)
				(type default)
			)
			(fill no)
			(layer "F.Fab")
		)
		(pad "1" smd custom
			(at 0 -0.4445 180)
			(size 0.1397 0.1397)
			(layers "F.Cu" "F.Mask" "F.Paste")
			(net "EJTAG_TCK_R")
			(options
				(clearance outline)
				(anchor circle)
			)
			(primitives
				(gr_poly
					(pts
						(arc
							(start -0.1778 -0.2794)
							(mid -0.249642 -0.249642)
							(end -0.2794 -0.1778)
						)
						(arc
							(start -0.2794 0.1778)
							(mid -0.249642 0.249642)
							(end -0.1778 0.2794)
						)
						(arc
							(start 0.1778 0.2794)
							(mid 0.249642 0.249642)
							(end 0.2794 0.1778)
						)
						(arc
							(start 0.2794 -0.1778)
							(mid 0.249642 -0.249642)
							(end 0.1778 -0.2794)
						)
					)
					(width 0)
					(fill yes)
				)
			)
		)
		(pad "2" smd custom
			(at 0 0.4445 180)
			(size 0.1397 0.1397)
			(layers "F.Cu" "F.Mask" "F.Paste")
			(net "EJTAG_TCK")
			(options
				(clearance outline)
				(anchor circle)
			)
			(primitives
				(gr_poly
					(pts
						(arc
							(start -0.1778 -0.2794)
							(mid -0.249642 -0.249642)
							(end -0.2794 -0.1778)
						)
						(arc
							(start -0.2794 0.1778)
							(mid -0.249642 0.249642)
							(end -0.1778 0.2794)
						)
						(arc
							(start 0.1778 0.2794)
							(mid 0.249642 0.249642)
							(end 0.2794 0.1778)
						)
						(arc
							(start 0.2794 -0.1778)
							(mid 0.249642 -0.249642)
							(end 0.1778 -0.2794)
						)
					)
					(width 0)
					(fill yes)
				)
			)
		)
	)
	(footprint ""
		(layer "F.Cu")
		(at 76.811124 -183.235092)
		(property "Reference" "R7943"
			(at 0 0 0)
			(layer "F.SilkS")
			(hide yes)
			(effects
				(font
					(size 1.27 1.27)
				)
			)
		)
		(property "Value" "0R2J-2-GP"
			(at 0.064008 -3.993896 0)
			(unlocked yes)
			(layer "F.Fab")
			(hide yes)
			(effects
				(font
					(size 1.016 1.016)
					(thickness 0.1524)
				)
			)
		)
		(property "Device Type" "R402H16"
			(at 0.064008 -5.517896 0)
			(unlocked yes)
			(layer "F.Fab")
			(hide yes)
			(effects
				(font
					(size 1.016 1.016)
					(thickness 0.1524)
				)
			)
		)
		(duplicate_pad_numbers_are_jumpers no)
		(fp_line
			(start -0.508 -0.9398)
			(end -0.508 0.9398)
			(stroke
				(width 0.1524)
				(type default)
			)
			(layer "F.SilkS")
		)
		(fp_line
			(start 0.508 -0.9398)
			(end -0.508 -0.9398)
			(stroke
				(width 0.1524)
				(type default)
			)
			(layer "F.SilkS")
		)
		(fp_rect
			(start -0.508 0.9398)
			(end 0.508 -0.9398)
			(stroke
				(width 0)
				(type default)
			)
			(fill no)
			(layer "F.CrtYd")
		)
		(fp_rect
			(start -0.508 0.9398)
			(end 0.508 -0.9398)
			(stroke
				(width 0)
				(type default)
			)
			(fill no)
			(layer "F.Fab")
		)
		(pad "1" smd custom
			(at 0 -0.4445)
			(size 0.1397 0.1397)
			(layers "F.Cu" "F.Mask" "F.Paste")
			(net "SSD_ATNLED#5")
			(options
				(clearance outline)
				(anchor circle)
			)
			(primitives
				(gr_poly
					(pts
						(arc
							(start -0.1778 -0.2794)
							(mid -0.249642 -0.249642)
							(end -0.2794 -0.1778)
						)
						(arc
							(start -0.2794 0.1778)
							(mid -0.249642 0.249642)
							(end -0.1778 0.2794)
						)
						(arc
							(start 0.1778 0.2794)
							(mid 0.249642 0.249642)
							(end 0.2794 0.1778)
						)
						(arc
							(start 0.2794 -0.1778)
							(mid 0.249642 -0.249642)
							(end 0.1778 -0.2794)
						)
					)
					(width 0)
					(fill yes)
				)
			)
		)
		(pad "2" smd custom
			(at 0 0.4445)
			(size 0.1397 0.1397)
			(layers "F.Cu" "F.Mask" "F.Paste")
			(net "SSD_ATNLED#5_R")
			(options
				(clearance outline)
				(anchor circle)
			)
			(primitives
				(gr_poly
					(pts
						(arc
							(start -0.1778 -0.2794)
							(mid -0.249642 -0.249642)
							(end -0.2794 -0.1778)
						)
						(arc
							(start -0.2794 0.1778)
							(mid -0.249642 0.249642)
							(end -0.1778 0.2794)
						)
						(arc
							(start 0.1778 0.2794)
							(mid 0.249642 0.249642)
							(end 0.2794 0.1778)
						)
						(arc
							(start 0.2794 -0.1778)
							(mid 0.249642 -0.249642)
							(end 0.1778 -0.2794)
						)
					)
					(width 0)
					(fill yes)
				)
			)
		)
	)
	(footprint ""
		(layer "F.Cu")
		(at 19.34718 -66.27368 180)
		(property "Reference" "R166"
			(at 0 0 180)
			(layer "F.SilkS")
			(hide yes)
			(effects
				(font
					(size 1.27 1.27)
				)
			)
		)
		(property "Value" "4K7R2F-GP"
			(at 0.064008 -3.993896 180)
			(unlocked yes)
			(layer "F.Fab")
			(hide yes)
			(effects
				(font
					(size 1.016 1.016)
					(thickness 0.1524)
				)
			)
		)
		(property "Device Type" "R402H16"
			(at 0.064008 -5.517896 180)
			(unlocked yes)
			(layer "F.Fab")
			(hide yes)
			(effects
				(font
					(size 1.016 1.016)
					(thickness 0.1524)
				)
			)
		)
		(duplicate_pad_numbers_are_jumpers no)
		(fp_line
			(start 0.508 -0.9398)
			(end -0.508 -0.9398)
			(stroke
				(width 0.1524)
				(type default)
			)
			(layer "F.SilkS")
		)
		(fp_line
			(start -0.508 -0.9398)
			(end -0.508 0.9398)
			(stroke
				(width 0.1524)
				(type default)
			)
			(layer "F.SilkS")
		)
		(fp_rect
			(start -0.508 0.9398)
			(end 0.508 -0.9398)
			(stroke
				(width 0)
				(type default)
			)
			(fill no)
			(layer "F.CrtYd")
		)
		(fp_rect
			(start -0.508 0.9398)
			(end 0.508 -0.9398)
			(stroke
				(width 0)
				(type default)
			)
			(fill no)
			(layer "F.Fab")
		)
		(pad "1" smd custom
			(at 0 -0.4445 180)
			(size 0.1397 0.1397)
			(layers "F.Cu" "F.Mask" "F.Paste")
			(net "GND")
			(options
				(clearance outline)
				(anchor circle)
			)
			(primitives
				(gr_poly
					(pts
						(arc
							(start -0.1778 -0.2794)
							(mid -0.249642 -0.249642)
							(end -0.2794 -0.1778)
						)
						(arc
							(start -0.2794 0.1778)
							(mid -0.249642 0.249642)
							(end -0.1778 0.2794)
						)
						(arc
							(start 0.1778 0.2794)
							(mid 0.249642 0.249642)
							(end 0.2794 0.1778)
						)
						(arc
							(start 0.2794 -0.1778)
							(mid 0.249642 -0.249642)
							(end 0.1778 -0.2794)
						)
					)
					(width 0)
					(fill yes)
				)
			)
		)
		(pad "2" smd custom
			(at 0 0.4445 180)
			(size 0.1397 0.1397)
			(layers "F.Cu" "F.Mask" "F.Paste")
			(net "PCIE_DIS")
			(options
				(clearance outline)
				(anchor circle)
			)
			(primitives
				(gr_poly
					(pts
						(arc
							(start -0.1778 -0.2794)
							(mid -0.249642 -0.249642)
							(end -0.2794 -0.1778)
						)
						(arc
							(start -0.2794 0.1778)
							(mid -0.249642 0.249642)
							(end -0.1778 0.2794)
						)
						(arc
							(start 0.1778 0.2794)
							(mid 0.249642 0.249642)
							(end 0.2794 0.1778)
						)
						(arc
							(start 0.2794 -0.1778)
							(mid 0.249642 -0.249642)
							(end 0.1778 -0.2794)
						)
					)
					(width 0)
					(fill yes)
				)
			)
		)
	)
)
